# T6G (Grand Teton) — schematic netlist excerpt (pin names and nets, part order shuffled) for the footprints in the layout excerpt that follows; sources: Cadence DE-HDL packaged netlist, KiCad conversion of 04192023_DAF0TMB3IC0_F0TG_MB_C_brd_V02_OCP.brd

PU22  ISL99390FRZTR5935  ISL99390FRZ-TR5935 IC  pkg QFN21_6X5XB  page 208
  VOS  = PVDD11_S3_P0_VOS1
  AGND  = GND
  VCC  = PVDD11_S3_P0_VCC1
  PVCC  = PVDD11_S3_P0_PVCC
  PGND1  = GND
  GL1  = NC_PVDD11_S3_P0_GL1_1
  PGND2  = GND
  SW  = SW_PVDD11_S3_P0_SW1
  VIN1  = SW_P12V_AUX_PVDD11_S3_P0_FLT
  VIN2  = SW_P12V_AUX_PVDD11_S3_P0_FLT
  DNC  = NC_PVDD11_S3_P0_DNC1
  PHASE  = SW_PVDD11_S3_P0_PH1
  BOOT  = SW_PVDD11_S3_P0_BOOT1
  PWM  = PVDD11_S3_P0_PWM1
  EN  = PVDD11_S3_P0_VCC1
  TOUT_FLT  = PVDD11_S3_P0_TEMP0
  LSET  = PVDD11_S3_P0_LSET1
  IOUT  = PVDD11_S3_P0_IMON1
  REFIN  = PVDD11_S3_P0_VCCS
  PGND3  = GND
  GL2  = NC_PVDD11_S3_P0_GL2_1

(kicad_pcb
	(version 20260206)
	(generator "pcbnew")
	(generator_version "10.0")
	(general
		(thickness 1.6)
		(legacy_teardrops no)
	)
	(paper "A4")
	(title_block
		(title "04192023_DAF0TMB3IC0_F0TG_MB_C_brd_V02_OCP.brd")
		(comment 1 "Grand Teton / footprints 1307-1307 of 8354")
	)
	(layers
		(0 "F.Cu" signal "TOP")
		(4 "In1.Cu" signal "GND")
		(6 "In2.Cu" signal "IN1")
		(8 "In3.Cu" signal "GND1")
		(10 "In4.Cu" signal "IN2")
		(12 "In5.Cu" signal "GND2")
		(14 "In6.Cu" signal "IN3")
		(16 "In7.Cu" signal "GND3")
		(18 "In8.Cu" signal "VCC")
		(20 "In9.Cu" signal "VCC1")
		(22 "In10.Cu" signal "GND4")
		(24 "In11.Cu" signal "IN4")
		(26 "In12.Cu" signal "GND5")
		(28 "In13.Cu" signal "IN5")
		(30 "In14.Cu" signal "GND6")
		(32 "In15.Cu" signal "IN6")
		(34 "In16.Cu" signal "GND7")
		(2 "B.Cu" signal "BOTTOM")
		(9 "F.Adhes" user "F.Adhesive")
		(11 "B.Adhes" user "B.Adhesive")
		(13 "F.Paste" user "Package Geometry/Pastemask Top")
		(15 "B.Paste" user "Package Geometry/Pastemask Bottom")
		(5 "F.SilkS" user "Ref Des/Silkscreen Top")
		(7 "B.SilkS" user "Ref Des/Silkscreen Bottom")
		(1 "F.Mask" user "Board Geometry/Soldermask Top")
		(3 "B.Mask" user "Board Geometry/Soldermask Bottom")
		(17 "Dwgs.User" user "User.Drawings")
		(19 "Cmts.User" user "User.Comments")
		(21 "Eco1.User" user "User.Eco1")
		(23 "Eco2.User" user "User.Eco2")
		(25 "Edge.Cuts" user "Board Geometry/Outline")
		(27 "Margin" user)
		(31 "F.CrtYd" user "Package Geometry/Place Bound Top")
		(29 "B.CrtYd" user "Package Geometry/Place Bound Bottom")
		(35 "F.Fab" user "Ref Des/Assembly Top")
		(33 "B.Fab" user "Ref Des/Assembly Bottom")
	)
	(footprint ""
		(layer "F.Cu")
		(at 423.64406 -351.114868)
		(property "Reference" "PU22"
			(at -5.372862 3.17627 90)
			(unlocked yes)
			(layer "F.SilkS")
			(effects
				(font
					(size 0.7874 0.5842)
					(thickness 0.1524)
				)
				(justify left)
			)
		)
		(property "Value" ""
			(at 0 0 0)
			(layer "F.Fab")
			(effects
				(font
					(size 1.27 1.27)
				)
			)
		)
		(duplicate_pad_numbers_are_jumpers no)
		(fp_line
			(start -2.500122 -2.999994)
			(end -2.24409 -2.999994)
			(stroke
				(width 0.1524)
				(type default)
			)
			(layer "F.SilkS")
		)
		(fp_line
			(start -2.500122 -2.529078)
			(end -2.500122 -2.999994)
			(stroke
				(width 0.1524)
				(type default)
			)
			(layer "F.SilkS")
		)
		(fp_line
			(start -2.500122 0.6604)
			(end -2.500122 0.229108)
			(stroke
				(width 0.1524)
				(type default)
			)
			(layer "F.SilkS")
		)
		(fp_line
			(start -2.500122 2.999994)
			(end -2.500122 2.339594)
			(stroke
				(width 0.1524)
				(type default)
			)
			(layer "F.SilkS")
		)
		(fp_line
			(start -2.2987 2.999994)
			(end -2.500122 2.999994)
			(stroke
				(width 0.1524)
				(type default)
			)
			(layer "F.SilkS")
		)
		(fp_line
			(start 2.31394 -2.999994)
			(end 2.500122 -2.999994)
			(stroke
				(width 0.1524)
				(type default)
			)
			(layer "F.SilkS")
		)
		(fp_line
			(start 2.500122 -2.999994)
			(end 2.500122 -2.44348)
			(stroke
				(width 0.1524)
				(type default)
			)
			(layer "F.SilkS")
		)
		(fp_line
			(start 2.500122 2.339594)
			(end 2.500122 2.999994)
			(stroke
				(width 0.1524)
				(type default)
			)
			(layer "F.SilkS")
		)
		(fp_line
			(start 2.500122 2.999994)
			(end 2.2987 2.999994)
			(stroke
				(width 0.1524)
				(type default)
			)
			(layer "F.SilkS")
		)
		(fp_poly
			(pts
				(xy -2.712974 -2.443988) (xy -3.386328 -2.668524) (xy -2.93751 -3.117596)
			)
			(stroke
				(width 0)
				(type default)
			)
			(fill yes)
			(layer "F.SilkS")
		)
		(fp_line
			(start -2.500122 -2.999994)
			(end 2.500122 -2.999994)
			(stroke
				(width 0.1)
				(type default)
			)
			(layer "F.Fab")
		)
		(fp_line
			(start -2.500122 2.999994)
			(end -2.500122 -2.999994)
			(stroke
				(width 0.1)
				(type default)
			)
			(layer "F.Fab")
		)
		(fp_line
			(start 2.500122 -2.999994)
			(end 2.500122 2.999994)
			(stroke
				(width 0.1)
				(type default)
			)
			(layer "F.Fab")
		)
		(fp_line
			(start 2.500122 2.999994)
			(end -2.500122 2.999994)
			(stroke
				(width 0.1)
				(type default)
			)
			(layer "F.Fab")
		)
		(fp_poly
			(pts
				(xy -4.218432 -2.783078) (xy -4.218432 -1.767078) (xy -3.202432 -2.275078)
			)
			(stroke
				(width 0)
				(type default)
			)
			(fill yes)
			(layer "F.Fab")
		)
		(pad "1" smd rect
			(at -2.400046 -2.275078 90)
			(size 0.2286 0.6096)
			(layers "F.Cu" "F.Mask" "F.Paste")
			(net "PVDD11_S3_P0_VOS1")
		)
		(pad "2" smd rect
			(at -2.400046 -1.82499 90)
			(size 0.2286 0.6096)
			(layers "F.Cu" "F.Mask" "F.Paste")
			(net "GND")
		)
		(pad "3" smd rect
			(at -2.400046 -1.374902 90)
			(size 0.2286 0.6096)
			(layers "F.Cu" "F.Mask" "F.Paste")
			(net "PVDD11_S3_P0_VCC1")
		)
		(pad "4" smd rect
			(at -2.400046 -0.925068 90)
			(size 0.2286 0.6096)
			(layers "F.Cu" "F.Mask" "F.Paste")
			(net "PVDD11_S3_P0_PVCC")
		)
		(pad "5" smd rect
			(at -2.400046 -0.47498 90)
			(size 0.2286 0.6096)
			(layers "F.Cu" "F.Mask" "F.Paste")
			(net "GND")
		)
		(pad "6" smd rect
			(at -2.400046 -0.024892 90)
			(size 0.2286 0.6096)
			(layers "F.Cu" "F.Mask" "F.Paste")
			(net "NC_PVDD11_S3_P0_GL1_1")
		)
		(pad "7_9-20_24" smd circle
			(at 0 1.150112 90)
			(size 0 0)
			(layers "F.Cu" "F.Mask" "F.Paste")
			(net "GND")
		)
		(pad "10_19" smd rect
			(at 0 2.899918 90)
			(size 0.6096 4.318)
			(layers "F.Cu" "F.Mask" "F.Paste")
			(net "SW_PVDD11_S3_P0_SW1")
		)
		(pad "25_29" smd rect
			(at 1.549908 -1.279906 270)
			(size 2.0574 2.3114)
			(layers "F.Cu" "F.Mask" "F.Paste")
			(net "SW_P12V_AUX_PVDD11_S3_P0_FLT")
		)
		(pad "30" smd rect
			(at 2.05994 -2.899918)
			(size 0.2286 0.6096)
			(layers "F.Cu" "F.Mask" "F.Paste")
			(net "SW_P12V_AUX_PVDD11_S3_P0_FLT")
		)
		(pad "31" smd rect
			(at 1.610106 -2.899918)
			(size 0.2286 0.6096)
			(layers "F.Cu" "F.Mask" "F.Paste")
			(net "NC_PVDD11_S3_P0_DNC1")
		)
		(pad "32" smd rect
			(at 1.160018 -2.899918)
			(size 0.2286 0.6096)
			(layers "F.Cu" "F.Mask" "F.Paste")
			(net "SW_PVDD11_S3_P0_PH1")
		)
		(pad "33" smd rect
			(at 0.70993 -2.899918)
			(size 0.2286 0.6096)
			(layers "F.Cu" "F.Mask" "F.Paste")
			(net "SW_PVDD11_S3_P0_BOOT1")
		)
		(pad "34" smd rect
			(at 0.260096 -2.899918)
			(size 0.2286 0.6096)
			(layers "F.Cu" "F.Mask" "F.Paste")
			(net "PVDD11_S3_P0_PWM1")
		)
		(pad "35" smd rect
			(at -0.189992 -2.899918)
			(size 0.2286 0.6096)
			(layers "F.Cu" "F.Mask" "F.Paste")
			(net "PVDD11_S3_P0_VCC1")
		)
		(pad "36" smd rect
			(at -0.64008 -2.899918)
			(size 0.2286 0.6096)
			(layers "F.Cu" "F.Mask" "F.Paste")
			(net "PVDD11_S3_P0_TEMP0")
		)
		(pad "37" smd rect
			(at -1.089914 -2.899918)
			(size 0.2286 0.6096)
			(layers "F.Cu" "F.Mask" "F.Paste")
			(net "PVDD11_S3_P0_LSET1")
		)
		(pad "38" smd rect
			(at -1.540002 -2.899918)
			(size 0.2286 0.6096)
			(layers "F.Cu" "F.Mask" "F.Paste")
			(net "PVDD11_S3_P0_IMON1")
		)
		(pad "39" smd rect
			(at -1.99009 -2.899918)
			(size 0.2286 0.6096)
			(layers "F.Cu" "F.Mask" "F.Paste")
			(net "PVDD11_S3_P0_VCCS")
		)
		(pad "40" smd rect
			(at -0.87503 -1.27508)
			(size 1.7526 1.9558)
			(layers "F.Cu" "F.Mask" "F.Paste")
			(net "GND")
		)
		(pad "41" smd rect
			(at -1.525016 0.249936 270)
			(size 0.3048 0.4572)
			(layers "F.Cu" "F.Mask" "F.Paste")
			(net "NC_PVDD11_S3_P0_GL2_1")
		)
		(zone
			(layer "F.Cu")
			(hatch none 0.5)
			(connect_pads
				(clearance 0)
			)
			(min_thickness 0.25)
			(keepout
				(tracks not_allowed)
				(vias allowed)
				(pads allowed)
				(copperpour not_allowed)
				(footprints allowed)
			)
			(placement
				(enabled no)
				(sheetname "")
			)
			(fill
				(thermal_gap 0.5)
				(thermal_bridge_width 0.5)
				(island_removal_mode 0)
			)
			(polygon
				(pts
					(xy 421.143938 -348.54007) (xy 421.143938 -348.864174) (xy 426.144182 -348.864174) (xy 426.144182 -348.114874)
					(xy 425.85386 -348.114874) (xy 425.85386 -348.57055) (xy 421.43426 -348.57055) (xy 421.43426 -348.54007)
				)
			)
		)
		(zone
			(layer "F.Cu")
			(hatch none 0.5)
			(connect_pads
				(clearance 0)
			)
			(min_thickness 0.25)
			(keepout
				(tracks not_allowed)
				(vias allowed)
				(pads allowed)
				(copperpour not_allowed)
				(footprints allowed)
			)
			(placement
				(enabled no)
				(sheetname "")
			)
			(fill
				(thermal_gap 0.5)
				(thermal_bridge_width 0.5)
				(island_removal_mode 0)
			)
			(polygon
				(pts
					(xy 423.69613 -351.361248) (xy 423.69613 -353.418648) (xy 421.84193 -353.418648) (xy 421.84193 -353.177602)
					(xy 421.599614 -353.177602) (xy 421.599614 -353.659186) (xy 425.4246 -353.659186) (xy 425.4246 -353.474274)
					(xy 423.987468 -353.474274) (xy 423.987468 -351.315274) (xy 426.144182 -351.315274) (xy 426.144182 -351.065592)
					(xy 423.991786 -351.065592)
				)
			)
		)
	)
)
